(kicad_pcb
	(version 20260206)
	(generator "pcbnew")
	(generator_version "10.0")
	(general
		(thickness 1.6)
		(legacy_teardrops no)
	)
	(paper "A4")
	(title_block
		(title "Bryce Canyon_F.DPB_16315-1-OCP.brd")
		(comment 1 "Bryce Canyon / footprints 1094-1100 of 2223")
	)
	(layers
		(0 "F.Cu" signal "TOP")
		(4 "In1.Cu" signal "L2GND")
		(6 "In2.Cu" signal "L3")
		(8 "In3.Cu" signal "L4GND")
		(10 "In4.Cu" signal "L5")
		(12 "In5.Cu" signal "L6VCC")
		(14 "In6.Cu" signal "L7VCC")
		(16 "In7.Cu" signal "L8")
		(18 "In8.Cu" signal "L9GND")
		(20 "In9.Cu" signal "L10")
		(22 "In10.Cu" signal "L11GND")
		(2 "B.Cu" signal "BOTTOM")
		(9 "F.Adhes" user "F.Adhesive")
		(11 "B.Adhes" user "B.Adhesive")
		(13 "F.Paste" user "Package Geometry/Pastemask Top")
		(15 "B.Paste" user "Package Geometry/Pastemask Bottom")
		(5 "F.SilkS" user "Ref Des/Silkscreen Top")
		(7 "B.SilkS" user "Ref Des/Silkscreen Bottom")
		(1 "F.Mask" user "Board Geometry/Soldermask Top")
		(3 "B.Mask" user "Board Geometry/Soldermask Bottom")
		(17 "Dwgs.User" user "User.Drawings")
		(19 "Cmts.User" user "User.Comments")
		(21 "Eco1.User" user "User.Eco1")
		(23 "Eco2.User" user "User.Eco2")
		(25 "Edge.Cuts" user "Board Geometry/Outline")
		(27 "Margin" user)
		(31 "F.CrtYd" user "Package Geometry/Place Bound Top")
		(29 "B.CrtYd" user "Package Geometry/Place Bound Bottom")
		(35 "F.Fab" user "Ref Des/Assembly Top")
		(33 "B.Fab" user "Ref Des/Assembly Bottom")
	)
	(footprint ""
		(layer "F.Cu")
		(at 323.2531 -46.437042)
		(property "Reference" "VIA70"
			(at 0 0 0)
			(layer "F.SilkS")
			(hide yes)
			(effects
				(font
					(size 1.27 1.27)
				)
			)
		)
		(property "Value" "100OHM-8L-1D6MM-L18L16-GP"
			(at -3.7211 -4.5085 0)
			(unlocked yes)
			(layer "F.Fab")
			(hide yes)
			(effects
				(font
					(size 1.016 1.016)
					(thickness 0.1524)
				)
			)
		)
		(property "Device Type" "VIA-PCIE-4P-394076"
			(at -3.7211 -6.0325 0)
			(unlocked yes)
			(layer "F.Fab")
			(hide yes)
			(effects
				(font
					(size 1.016 1.016)
					(thickness 0.1524)
				)
			)
		)
		(duplicate_pad_numbers_are_jumpers no)
		(fp_rect
			(start -1.9685 0.381)
			(end 1.9685 -0.381)
			(stroke
				(width 0)
				(type default)
			)
			(fill no)
			(layer "F.CrtYd")
		)
		(fp_rect
			(start -1.9685 0.381)
			(end 1.9685 -0.381)
			(stroke
				(width 0)
				(type default)
			)
			(fill no)
			(layer "F.Fab")
		)
		(pad "1" thru_hole circle
			(at -1.5875 0)
			(size 0.508 0.508)
			(drill 0.254)
			(layers "*.Cu" "*.Mask")
			(remove_unused_layers no)
			(net "GND")
			(clearance 0.127)
			(thermal_gap 0.127)
		)
		(pad "2" thru_hole circle
			(at -0.5715 0)
			(size 0.508 0.508)
			(drill 0.254)
			(layers "*.Cu" "*.Mask")
			(remove_unused_layers no)
			(net "PHY_DRV_A_TO_SCC_A_30_DP")
			(clearance 0.127)
			(thermal_gap 0.127)
		)
		(pad "3" thru_hole circle
			(at 0.5715 0)
			(size 0.508 0.508)
			(drill 0.254)
			(layers "*.Cu" "*.Mask")
			(remove_unused_layers no)
			(net "PHY_DRV_A_TO_SCC_A_30_DN")
			(clearance 0.127)
			(thermal_gap 0.127)
		)
		(pad "4" thru_hole circle
			(at 1.5875 0)
			(size 0.508 0.508)
			(drill 0.254)
			(layers "*.Cu" "*.Mask")
			(remove_unused_layers no)
			(net "GND")
			(clearance 0.127)
			(thermal_gap 0.127)
		)
	)
	(footprint ""
		(layer "F.Cu")
		(at 133.497066 -137.993374)
		(property "Reference" "R1006"
			(at 0 0 0)
			(layer "F.SilkS")
			(hide yes)
			(effects
				(font
					(size 1.27 1.27)
				)
			)
		)
		(property "Value" "100KR2F-L1-GP"
			(at 0.064008 -3.993896 0)
			(unlocked yes)
			(layer "F.Fab")
			(hide yes)
			(effects
				(font
					(size 1.016 1.016)
					(thickness 0.1524)
				)
			)
		)
		(property "Device Type" "R402H16"
			(at 0.064008 -5.517896 0)
			(unlocked yes)
			(layer "F.Fab")
			(hide yes)
			(effects
				(font
					(size 1.016 1.016)
					(thickness 0.1524)
				)
			)
		)
		(duplicate_pad_numbers_are_jumpers no)
		(fp_line
			(start -0.508 -0.9398)
			(end -0.508 0.9398)
			(stroke
				(width 0.1524)
				(type default)
			)
			(layer "F.SilkS")
		)
		(fp_line
			(start 0.508 -0.9398)
			(end -0.508 -0.9398)
			(stroke
				(width 0.1524)
				(type default)
			)
			(layer "F.SilkS")
		)
		(fp_rect
			(start -0.508 0.9398)
			(end 0.508 -0.9398)
			(stroke
				(width 0)
				(type default)
			)
			(fill no)
			(layer "F.CrtYd")
		)
		(fp_rect
			(start -0.508 0.9398)
			(end 0.508 -0.9398)
			(stroke
				(width 0)
				(type default)
			)
			(fill no)
			(layer "F.Fab")
		)
		(pad "1" smd custom
			(at 0 -0.4445)
			(size 0.1397 0.1397)
			(layers "F.Cu" "F.Mask" "F.Paste")
			(net "COMP_A_PWR_EN")
			(options
				(clearance outline)
				(anchor circle)
			)
			(primitives
				(gr_poly
					(pts
						(arc
							(start -0.1778 -0.2794)
							(mid -0.249642 -0.249642)
							(end -0.2794 -0.1778)
						)
						(arc
							(start -0.2794 0.1778)
							(mid -0.249642 0.249642)
							(end -0.1778 0.2794)
						)
						(arc
							(start 0.1778 0.2794)
							(mid 0.249642 0.249642)
							(end 0.2794 0.1778)
						)
						(arc
							(start 0.2794 -0.1778)
							(mid 0.249642 -0.249642)
							(end 0.1778 -0.2794)
						)
					)
					(width 0)
					(fill yes)
				)
			)
		)
		(pad "2" smd custom
			(at 0 0.4445)
			(size 0.1397 0.1397)
			(layers "F.Cu" "F.Mask" "F.Paste")
			(net "GND")
			(options
				(clearance outline)
				(anchor circle)
			)
			(primitives
				(gr_poly
					(pts
						(arc
							(start -0.1778 -0.2794)
							(mid -0.249642 -0.249642)
							(end -0.2794 -0.1778)
						)
						(arc
							(start -0.2794 0.1778)
							(mid -0.249642 0.249642)
							(end -0.1778 0.2794)
						)
						(arc
							(start 0.1778 0.2794)
							(mid 0.249642 0.249642)
							(end 0.2794 0.1778)
						)
						(arc
							(start 0.2794 -0.1778)
							(mid 0.249642 -0.249642)
							(end 0.1778 -0.2794)
						)
					)
					(width 0)
					(fill yes)
				)
			)
		)
	)
	(footprint ""
		(layer "F.Cu")
		(at 300.19498 -243.19992)
		(property "Reference" ""
			(at 0 0 0)
			(layer "F.SilkS")
			(hide yes)
			(effects
				(font
					(size 1.27 1.27)
				)
			)
		)
		(property "Value" "*"
			(at -8.398764 -8.057642 0)
			(unlocked yes)
			(layer "F.Fab")
			(hide yes)
			(effects
				(font
					(size 1.016 1.016)
					(thickness 0.1524)
				)
			)
		)
		(duplicate_pad_numbers_are_jumpers no)
		(fp_poly
			(pts
				(arc
					(start 7.3152 0)
					(mid 0 7.3152)
					(end -7.3152 0)
				)
				(arc
					(start -7.3152 -5.9944)
					(mid 0 -13.3096)
					(end 7.3152 -5.9944)
				)
			)
			(stroke
				(width 0)
				(type default)
			)
			(fill no)
			(layer "B.CrtYd")
		)
		(fp_poly
			(pts
				(arc
					(start 7.3152 0)
					(mid 0 7.3152)
					(end -7.3152 0)
				)
				(arc
					(start -7.3152 -5.9944)
					(mid 0 -13.3096)
					(end 7.3152 -5.9944)
				)
			)
			(stroke
				(width 0)
				(type default)
			)
			(fill no)
			(layer "F.CrtYd")
		)
		(fp_poly
			(pts
				(arc
					(start 7.3152 0)
					(mid 0 7.3152)
					(end -7.3152 0)
				)
				(arc
					(start -7.3152 -5.9944)
					(mid 0 -13.3096)
					(end 7.3152 -5.9944)
				)
			)
			(stroke
				(width 0)
				(type default)
			)
			(fill no)
			(layer "B.Fab")
		)
		(fp_poly
			(pts
				(arc
					(start 7.3152 0)
					(mid 0 7.3152)
					(end -7.3152 0)
				)
				(arc
					(start -7.3152 -5.9944)
					(mid 0 -13.3096)
					(end 7.3152 -5.9944)
				)
			)
			(stroke
				(width 0)
				(type default)
			)
			(fill no)
			(layer "F.Fab")
		)
		(pad "1" thru_hole oval
			(at 0 0)
			(size 14.0208 20.0152)
			(drill 0.0254
				(offset 0 -2.9972)
			)
			(layers "*.Cu" "*.Mask")
			(remove_unused_layers no)
			(net "Net_64")
			(clearance -1.002284)
			(thermal_gap 0.1524)
			(padstack
				(mode front_inner_back)
				(layer "Inner"
					(shape custom)
					(size 2.928012 2.928012)
					(options
						(anchor circle)
					)
					(primitives
						(gr_poly
							(pts
								(arc
									(start 4.571746 -2.084324)
									(mid 0.000333 7.430372)
									(end -4.571492 -2.084324)
								)
								(arc
									(start -4.571492 -2.084324)
									(mid -3.570296 -3.611977)
									(end -2.875026 -5.30098)
								)
								(arc
									(start -2.875026 -5.30098)
									(mid 0.000217 -7.43089)
									(end 2.87528 -5.30098)
								)
								(arc
									(start 2.87528 -5.30098)
									(mid 3.570511 -3.611956)
									(end 4.571746 -2.084324)
								)
							)
							(width 0)
							(fill yes)
						)
					)
					(clearance 0.1524)
				)
				(layer "B.Cu"
					(shape oval)
					(size 14.0208 20.0152)
					(offset 0 -2.9972)
					(clearance -1.002284)
				)
			)
		)
		(zone
			(layers "F.Cu" "B.Cu" "In1.Cu" "In2.Cu" "In3.Cu" "In4.Cu" "In5.Cu" "In6.Cu"
				"In7.Cu" "In8.Cu" "In9.Cu" "In10.Cu"
			)
			(hatch none 0.5)
			(connect_pads
				(clearance 0)
			)
			(min_thickness 0.25)
			(keepout
				(tracks not_allowed)
				(vias allowed)
				(pads allowed)
				(copperpour not_allowed)
				(footprints allowed)
			)
			(placement
				(enabled no)
				(sheetname "")
			)
			(fill
				(thermal_gap 0.5)
				(thermal_bridge_width 0.5)
				(island_removal_mode 0)
			)
			(polygon
				(pts
					(arc
						(start 293.18458 -249.19432)
						(mid 300.19498 -256.20472)
						(end 307.20538 -249.19432)
					)
					(arc
						(start 307.20538 -243.19992)
						(mid 300.19498 -236.18952)
						(end 293.18458 -243.19992)
					)
				)
			)
		)
	)
	(footprint ""
		(layer "F.Cu")
		(at 15.223998 -277.157942 180)
		(property "Reference" "R974"
			(at 0 0 180)
			(layer "F.SilkS")
			(hide yes)
			(effects
				(font
					(size 1.27 1.27)
				)
			)
		)
		(property "Value" "200KR2F-L-GP"
			(at 0.064008 -3.993896 180)
			(unlocked yes)
			(layer "F.Fab")
			(hide yes)
			(effects
				(font
					(size 1.016 1.016)
					(thickness 0.1524)
				)
			)
		)
		(property "Device Type" "R402H16"
			(at 0.064008 -5.517896 180)
			(unlocked yes)
			(layer "F.Fab")
			(hide yes)
			(effects
				(font
					(size 1.016 1.016)
					(thickness 0.1524)
				)
			)
		)
		(duplicate_pad_numbers_are_jumpers no)
		(fp_line
			(start 0.508 -0.9398)
			(end -0.508 -0.9398)
			(stroke
				(width 0.1524)
				(type default)
			)
			(layer "F.SilkS")
		)
		(fp_line
			(start -0.508 -0.9398)
			(end -0.508 0.9398)
			(stroke
				(width 0.1524)
				(type default)
			)
			(layer "F.SilkS")
		)
		(fp_rect
			(start -0.508 0.9398)
			(end 0.508 -0.9398)
			(stroke
				(width 0)
				(type default)
			)
			(fill no)
			(layer "F.CrtYd")
		)
		(fp_rect
			(start -0.508 0.9398)
			(end 0.508 -0.9398)
			(stroke
				(width 0)
				(type default)
			)
			(fill no)
			(layer "F.Fab")
		)
		(pad "1" smd custom
			(at 0 -0.4445 180)
			(size 0.1397 0.1397)
			(layers "F.Cu" "F.Mask" "F.Paste")
			(net "SW_HDD_R0")
			(options
				(clearance outline)
				(anchor circle)
			)
			(primitives
				(gr_poly
					(pts
						(arc
							(start -0.1778 -0.2794)
							(mid -0.249642 -0.249642)
							(end -0.2794 -0.1778)
						)
						(arc
							(start -0.2794 0.1778)
							(mid -0.249642 0.249642)
							(end -0.1778 0.2794)
						)
						(arc
							(start 0.1778 0.2794)
							(mid 0.249642 0.249642)
							(end 0.2794 0.1778)
						)
						(arc
							(start 0.2794 -0.1778)
							(mid 0.249642 -0.249642)
							(end 0.1778 -0.2794)
						)
					)
					(width 0)
					(fill yes)
				)
			)
		)
		(pad "2" smd custom
			(at 0 0.4445 180)
			(size 0.1397 0.1397)
			(layers "F.Cu" "F.Mask" "F.Paste")
			(net "SW_HDD_N0")
			(options
				(clearance outline)
				(anchor circle)
			)
			(primitives
				(gr_poly
					(pts
						(arc
							(start -0.1778 -0.2794)
							(mid -0.249642 -0.249642)
							(end -0.2794 -0.1778)
						)
						(arc
							(start -0.2794 0.1778)
							(mid -0.249642 0.249642)
							(end -0.1778 0.2794)
						)
						(arc
							(start 0.1778 0.2794)
							(mid 0.249642 0.249642)
							(end 0.2794 0.1778)
						)
						(arc
							(start 0.2794 -0.1778)
							(mid 0.249642 -0.249642)
							(end 0.1778 -0.2794)
						)
					)
					(width 0)
					(fill yes)
				)
			)
		)
	)
	(footprint ""
		(layer "F.Cu")
		(at 447.834512 -273.660616 -90)
		(property "Reference" "C169"
			(at 0 0 270)
			(layer "F.SilkS")
			(hide yes)
			(effects
				(font
					(size 1.27 1.27)
				)
			)
		)
		(property "Value" "SCD01U16V1KX-GP"
			(at -2.8321 -1.7399 270)
			(unlocked yes)
			(layer "F.Fab")
			(hide yes)
			(effects
				(font
					(size 1.016 1.016)
					(thickness 0.1524)
				)
			)
		)
		(property "Device Type" "C0201H13"
			(at -2.8321 -3.2639 270)
			(unlocked yes)
			(layer "F.Fab")
			(hide yes)
			(effects
				(font
					(size 1.016 1.016)
					(thickness 0.1524)
				)
			)
		)
		(duplicate_pad_numbers_are_jumpers no)
		(fp_rect
			(start -0.2794 0.6477)
			(end 0.2794 -0.6477)
			(stroke
				(width 0)
				(type default)
			)
			(fill no)
			(layer "F.CrtYd")
		)
		(fp_rect
			(start -0.2794 0.6477)
			(end 0.2794 -0.6477)
			(stroke
				(width 0)
				(type default)
			)
			(fill no)
			(layer "F.Fab")
		)
		(pad "1" smd custom
			(at 0 -0.2794 270)
			(size 0.0762 0.0762)
			(layers "F.Cu" "F.Mask" "F.Paste")
			(net "SAS_HDD_RX_P10")
			(options
				(clearance outline)
				(anchor circle)
			)
			(primitives
				(gr_poly
					(pts
						(arc
							(start 0.1524 -0.127)
							(mid 0.137521 -0.162921)
							(end 0.1016 -0.1778)
						)
						(arc
							(start -0.1016 -0.1778)
							(mid -0.137521 -0.162921)
							(end -0.1524 -0.127)
						)
						(arc
							(start -0.1524 0.127)
							(mid -0.137521 0.162921)
							(end -0.1016 0.1778)
						)
						(arc
							(start 0.1016 0.1778)
							(mid 0.137521 0.162921)
							(end 0.1524 0.127)
						)
					)
					(width 0)
					(fill yes)
				)
			)
		)
		(pad "2" smd custom
			(at 0 0.2794 270)
			(size 0.0762 0.0762)
			(layers "F.Cu" "F.Mask" "F.Paste")
			(net "PHY_SCC_A_TO_DRV_A_10_DP")
			(options
				(clearance outline)
				(anchor circle)
			)
			(primitives
				(gr_poly
					(pts
						(arc
							(start 0.1524 -0.127)
							(mid 0.137521 -0.162921)
							(end 0.1016 -0.1778)
						)
						(arc
							(start -0.1016 -0.1778)
							(mid -0.137521 -0.162921)
							(end -0.1524 -0.127)
						)
						(arc
							(start -0.1524 0.127)
							(mid -0.137521 0.162921)
							(end -0.1016 0.1778)
						)
						(arc
							(start 0.1016 0.1778)
							(mid 0.137521 0.162921)
							(end 0.1524 0.127)
						)
					)
					(width 0)
					(fill yes)
				)
			)
		)
	)
	(footprint ""
		(layer "F.Cu")
		(at 161.997898 -62.169294 -90)
		(property "Reference" "R774"
			(at 0 0 270)
			(layer "F.SilkS")
			(hide yes)
			(effects
				(font
					(size 1.27 1.27)
				)
			)
		)
		(property "Value" "10KR2F-2-GP"
			(at 0.064008 -3.993896 270)
			(unlocked yes)
			(layer "F.Fab")
			(hide yes)
			(effects
				(font
					(size 1.016 1.016)
					(thickness 0.1524)
				)
			)
		)
		(property "Device Type" "R402H16"
			(at 0.064008 -5.517896 270)
			(unlocked yes)
			(layer "F.Fab")
			(hide yes)
			(effects
				(font
					(size 1.016 1.016)
					(thickness 0.1524)
				)
			)
		)
		(duplicate_pad_numbers_are_jumpers no)
		(fp_line
			(start -0.508 -0.9398)
			(end -0.508 0.9398)
			(stroke
				(width 0.1524)
				(type default)
			)
			(layer "F.SilkS")
		)
		(fp_line
			(start 0.508 -0.9398)
			(end -0.508 -0.9398)
			(stroke
				(width 0.1524)
				(type default)
			)
			(layer "F.SilkS")
		)
		(fp_rect
			(start -0.508 0.9398)
			(end 0.508 -0.9398)
			(stroke
				(width 0)
				(type default)
			)
			(fill no)
			(layer "F.CrtYd")
		)
		(fp_rect
			(start -0.508 0.9398)
			(end 0.508 -0.9398)
			(stroke
				(width 0)
				(type default)
			)
			(fill no)
			(layer "F.Fab")
		)
		(pad "1" smd custom
			(at 0 -0.4445 270)
			(size 0.1397 0.1397)
			(layers "F.Cu" "F.Mask" "F.Paste")
			(net "P3V3_STBY_A")
			(options
				(clearance outline)
				(anchor circle)
			)
			(primitives
				(gr_poly
					(pts
						(arc
							(start -0.1778 -0.2794)
							(mid -0.249642 -0.249642)
							(end -0.2794 -0.1778)
						)
						(arc
							(start -0.2794 0.1778)
							(mid -0.249642 0.249642)
							(end -0.1778 0.2794)
						)
						(arc
							(start 0.1778 0.2794)
							(mid 0.249642 0.249642)
							(end 0.2794 0.1778)
						)
						(arc
							(start 0.2794 -0.1778)
							(mid 0.249642 -0.249642)
							(end 0.1778 -0.2794)
						)
					)
					(width 0)
					(fill yes)
				)
			)
		)
		(pad "2" smd custom
			(at 0 0.4445 270)
			(size 0.1397 0.1397)
			(layers "F.Cu" "F.Mask" "F.Paste")
			(net "HDD_PRSNT_28")
			(options
				(clearance outline)
				(anchor circle)
			)
			(primitives
				(gr_poly
					(pts
						(arc
							(start -0.1778 -0.2794)
							(mid -0.249642 -0.249642)
							(end -0.2794 -0.1778)
						)
						(arc
							(start -0.2794 0.1778)
							(mid -0.249642 0.249642)
							(end -0.1778 0.2794)
						)
						(arc
							(start 0.1778 0.2794)
							(mid 0.249642 0.249642)
							(end 0.2794 0.1778)
						)
						(arc
							(start 0.2794 -0.1778)
							(mid 0.249642 -0.249642)
							(end 0.1778 -0.2794)
						)
					)
					(width 0)
					(fill yes)
				)
			)
		)
	)
	(footprint ""
		(layer "F.Cu")
		(at 433.359052 -56.809894 -90)
		(property "Reference" "R903"
			(at 0 0 270)
			(layer "F.SilkS")
			(hide yes)
			(effects
				(font
					(size 1.27 1.27)
				)
			)
		)
		(property "Value" "300KR2F-GP"
			(at 0.064008 -3.993896 270)
			(unlocked yes)
			(layer "F.Fab")
			(hide yes)
			(effects
				(font
					(size 1.016 1.016)
					(thickness 0.1524)
				)
			)
		)
		(property "Device Type" "R402H16"
			(at 0.064008 -5.517896 270)
			(unlocked yes)
			(layer "F.Fab")
			(hide yes)
			(effects
				(font
					(size 1.016 1.016)
					(thickness 0.1524)
				)
			)
		)
		(duplicate_pad_numbers_are_jumpers no)
		(fp_line
			(start -0.508 -0.9398)
			(end -0.508 0.9398)
			(stroke
				(width 0.1524)
				(type default)
			)
			(layer "F.SilkS")
		)
		(fp_line
			(start 0.508 -0.9398)
			(end -0.508 -0.9398)
			(stroke
				(width 0.1524)
				(type default)
			)
			(layer "F.SilkS")
		)
		(fp_rect
			(start -0.508 0.9398)
			(end 0.508 -0.9398)
			(stroke
				(width 0)
				(type default)
			)
			(fill no)
			(layer "F.CrtYd")
		)
		(fp_rect
			(start -0.508 0.9398)
			(end 0.508 -0.9398)
			(stroke
				(width 0)
				(type default)
			)
			(fill no)
			(layer "F.Fab")
		)
		(pad "1" smd custom
			(at 0 -0.4445 270)
			(size 0.1397 0.1397)
			(layers "F.Cu" "F.Mask" "F.Paste")
			(net "SW_HDD_N33")
			(options
				(clearance outline)
				(anchor circle)
			)
			(primitives
				(gr_poly
					(pts
						(arc
							(start -0.1778 -0.2794)
							(mid -0.249642 -0.249642)
							(end -0.2794 -0.1778)
						)
						(arc
							(start -0.2794 0.1778)
							(mid -0.249642 0.249642)
							(end -0.1778 0.2794)
						)
						(arc
							(start 0.1778 0.2794)
							(mid 0.249642 0.249642)
							(end 0.2794 0.1778)
						)
						(arc
							(start 0.2794 -0.1778)
							(mid 0.249642 -0.249642)
							(end 0.1778 -0.2794)
						)
					)
					(width 0)
					(fill yes)
				)
			)
		)
		(pad "2" smd custom
			(at 0 0.4445 270)
			(size 0.1397 0.1397)
			(layers "F.Cu" "F.Mask" "F.Paste")
			(net "P12V_A")
			(options
				(clearance outline)
				(anchor circle)
			)
			(primitives
				(gr_poly
					(pts
						(arc
							(start -0.1778 -0.2794)
							(mid -0.249642 -0.249642)
							(end -0.2794 -0.1778)
						)
						(arc
							(start -0.2794 0.1778)
							(mid -0.249642 0.249642)
							(end -0.1778 0.2794)
						)
						(arc
							(start 0.1778 0.2794)
							(mid 0.249642 0.249642)
							(end 0.2794 0.1778)
						)
						(arc
							(start 0.2794 -0.1778)
							(mid 0.249642 -0.249642)
							(end 0.1778 -0.2794)
						)
					)
					(width 0)
					(fill yes)
				)
			)
		)
	)
)
